# S9S_MB_2U (Grand Teton) — schematic netlist excerpt (pin names and nets, part order shuffled) for the footprints in the layout excerpt that follows; sources: Cadence DE-HDL packaged netlist, KiCad conversion of 03242023_DA0F0TMBIJ0_F0T_Motherboard_J_brd_V01_OCP.brd

PC1343  Q_CAP  0.1UF 25V 10% X7R  pkg 0402  page 269 : A = GND ; B = PVCCIN_CPU0_VREF
C2048  Q_CAP  0.1UF 25V 10% X7R  pkg 0402  page 250 : A = P3V3_ADC_TIC ; B = GND

(kicad_pcb
	(version 20260206)
	(generator "pcbnew")
	(generator_version "10.0")
	(general
		(thickness 1.6)
		(legacy_teardrops no)
	)
	(paper "A4")
	(title_block
		(title "03242023_DA0F0TMBIJ0_F0T_Motherboard_J_brd_V01_OCP.brd")
		(comment 1 "Grand Teton / footprints 1765-1766 of 6105")
	)
	(layers
		(0 "F.Cu" signal "TOP")
		(4 "In1.Cu" signal "GND")
		(6 "In2.Cu" signal "IN1")
		(8 "In3.Cu" signal "GND1")
		(10 "In4.Cu" signal "IN2")
		(12 "In5.Cu" signal "GND2")
		(14 "In6.Cu" signal "IN3")
		(16 "In7.Cu" signal "GND3")
		(18 "In8.Cu" signal "VCC")
		(20 "In9.Cu" signal "VCC1")
		(22 "In10.Cu" signal "GND4")
		(24 "In11.Cu" signal "IN4")
		(26 "In12.Cu" signal "GND5")
		(28 "In13.Cu" signal "IN5")
		(30 "In14.Cu" signal "GND6")
		(32 "In15.Cu" signal "IN6")
		(34 "In16.Cu" signal "GND7")
		(2 "B.Cu" signal "BOTTOM")
		(9 "F.Adhes" user "F.Adhesive")
		(11 "B.Adhes" user "B.Adhesive")
		(13 "F.Paste" user "Package Geometry/Pastemask Top")
		(15 "B.Paste" user "Package Geometry/Pastemask Bottom")
		(5 "F.SilkS" user "Ref Des/Silkscreen Top")
		(7 "B.SilkS" user "Ref Des/Silkscreen Bottom")
		(1 "F.Mask" user "Board Geometry/Soldermask Top")
		(3 "B.Mask" user "Board Geometry/Soldermask Bottom")
		(17 "Dwgs.User" user "User.Drawings")
		(19 "Cmts.User" user "User.Comments")
		(21 "Eco1.User" user "User.Eco1")
		(23 "Eco2.User" user "User.Eco2")
		(25 "Edge.Cuts" user "Board Geometry/Outline")
		(27 "Margin" user)
		(31 "F.CrtYd" user "Package Geometry/Place Bound Top")
		(29 "B.CrtYd" user "Package Geometry/Place Bound Bottom")
		(35 "F.Fab" user "Ref Des/Assembly Top")
		(33 "B.Fab" user "Ref Des/Assembly Bottom")
	)
	(footprint ""
		(layer "F.Cu")
		(at 36.930584 -108.555282)
		(property "Reference" "C2048"
			(at 0 0 0)
			(layer "F.SilkS")
			(hide yes)
			(effects
				(font
					(size 1.27 1.27)
				)
			)
		)
		(property "Value" ""
			(at 0 0 0)
			(layer "F.Fab")
			(effects
				(font
					(size 1.27 1.27)
				)
			)
		)
		(duplicate_pad_numbers_are_jumpers no)
		(fp_line
			(start -0.7874 -0.4064)
			(end 0.7874 -0.4064)
			(stroke
				(width 0.1524)
				(type default)
			)
			(layer "F.SilkS")
		)
		(fp_line
			(start -0.7874 0.4064)
			(end -0.7874 -0.4064)
			(stroke
				(width 0.1524)
				(type default)
			)
			(layer "F.SilkS")
		)
		(fp_line
			(start 0.7874 -0.4064)
			(end 0.7874 0.4064)
			(stroke
				(width 0.1524)
				(type default)
			)
			(layer "F.SilkS")
		)
		(fp_line
			(start 0.7874 0.4064)
			(end -0.7874 0.4064)
			(stroke
				(width 0.1524)
				(type default)
			)
			(layer "F.SilkS")
		)
		(fp_line
			(start -0.67945 -0.305054)
			(end -0.12065 -0.305054)
			(stroke
				(width 0.1)
				(type default)
			)
			(layer "F.Fab")
		)
		(fp_line
			(start -0.67945 0.3048)
			(end -0.67945 -0.305054)
			(stroke
				(width 0.1)
				(type default)
			)
			(layer "F.Fab")
		)
		(fp_line
			(start -0.12065 -0.305054)
			(end -0.12065 -0.2794)
			(stroke
				(width 0.1)
				(type default)
			)
			(layer "F.Fab")
		)
		(fp_line
			(start -0.12065 -0.2794)
			(end 0.12065 -0.2794)
			(stroke
				(width 0.1)
				(type default)
			)
			(layer "F.Fab")
		)
		(fp_line
			(start -0.12065 0.2794)
			(end -0.12065 0.3048)
			(stroke
				(width 0.1)
				(type default)
			)
			(layer "F.Fab")
		)
		(fp_line
			(start -0.12065 0.3048)
			(end -0.67945 0.3048)
			(stroke
				(width 0.1)
				(type default)
			)
			(layer "F.Fab")
		)
		(fp_line
			(start 0.120396 0.2794)
			(end -0.12065 0.2794)
			(stroke
				(width 0.1)
				(type default)
			)
			(layer "F.Fab")
		)
		(fp_line
			(start 0.120396 0.3048)
			(end 0.120396 0.2794)
			(stroke
				(width 0.1)
				(type default)
			)
			(layer "F.Fab")
		)
		(fp_line
			(start 0.12065 -0.3048)
			(end 0.67945 -0.3048)
			(stroke
				(width 0.1)
				(type default)
			)
			(layer "F.Fab")
		)
		(fp_line
			(start 0.12065 -0.2794)
			(end 0.12065 -0.3048)
			(stroke
				(width 0.1)
				(type default)
			)
			(layer "F.Fab")
		)
		(fp_line
			(start 0.67945 -0.3048)
			(end 0.67945 0.3048)
			(stroke
				(width 0.1)
				(type default)
			)
			(layer "F.Fab")
		)
		(fp_line
			(start 0.67945 0.3048)
			(end 0.120396 0.3048)
			(stroke
				(width 0.1)
				(type default)
			)
			(layer "F.Fab")
		)
		(pad "1" smd circle
			(at -0.40005 0)
			(size 0 0)
			(layers "F.Cu" "F.Mask" "F.Paste")
			(net "P3V3_ADC_TIC")
		)
		(pad "2" smd circle
			(at 0.40005 0)
			(size 0 0)
			(layers "F.Cu" "F.Mask" "F.Paste")
			(net "GND")
		)
	)
	(footprint ""
		(layer "F.Cu")
		(at 374.802146 -341.716106 -90)
		(property "Reference" "PC1343"
			(at 0 0 270)
			(layer "F.SilkS")
			(hide yes)
			(effects
				(font
					(size 1.27 1.27)
				)
			)
		)
		(property "Value" ""
			(at 0 0 270)
			(layer "F.Fab")
			(effects
				(font
					(size 1.27 1.27)
				)
			)
		)
		(duplicate_pad_numbers_are_jumpers no)
		(fp_line
			(start -0.7874 0.4064)
			(end -0.7874 -0.4064)
			(stroke
				(width 0.1524)
				(type default)
			)
			(layer "F.SilkS")
		)
		(fp_line
			(start 0.7874 0.4064)
			(end -0.7874 0.4064)
			(stroke
				(width 0.1524)
				(type default)
			)
			(layer "F.SilkS")
		)
		(fp_line
			(start -0.7874 -0.4064)
			(end 0.7874 -0.4064)
			(stroke
				(width 0.1524)
				(type default)
			)
			(layer "F.SilkS")
		)
		(fp_line
			(start 0.7874 -0.4064)
			(end 0.7874 0.4064)
			(stroke
				(width 0.1524)
				(type default)
			)
			(layer "F.SilkS")
		)
		(fp_line
			(start -0.67945 0.3048)
			(end -0.67945 -0.305054)
			(stroke
				(width 0.1)
				(type default)
			)
			(layer "F.Fab")
		)
		(fp_line
			(start -0.12065 0.3048)
			(end -0.67945 0.3048)
			(stroke
				(width 0.1)
				(type default)
			)
			(layer "F.Fab")
		)
		(fp_line
			(start 0.120396 0.3048)
			(end 0.120396 0.2794)
			(stroke
				(width 0.1)
				(type default)
			)
			(layer "F.Fab")
		)
		(fp_line
			(start 0.67945 0.3048)
			(end 0.120396 0.3048)
			(stroke
				(width 0.1)
				(type default)
			)
			(layer "F.Fab")
		)
		(fp_line
			(start -0.12065 0.2794)
			(end -0.12065 0.3048)
			(stroke
				(width 0.1)
				(type default)
			)
			(layer "F.Fab")
		)
		(fp_line
			(start 0.120396 0.2794)
			(end -0.12065 0.2794)
			(stroke
				(width 0.1)
				(type default)
			)
			(layer "F.Fab")
		)
		(fp_line
			(start -0.12065 -0.2794)
			(end 0.12065 -0.2794)
			(stroke
				(width 0.1)
				(type default)
			)
			(layer "F.Fab")
		)
		(fp_line
			(start 0.12065 -0.2794)
			(end 0.12065 -0.3048)
			(stroke
				(width 0.1)
				(type default)
			)
			(layer "F.Fab")
		)
		(fp_line
			(start 0.12065 -0.3048)
			(end 0.67945 -0.3048)
			(stroke
				(width 0.1)
				(type default)
			)
			(layer "F.Fab")
		)
		(fp_line
			(start 0.67945 -0.3048)
			(end 0.67945 0.3048)
			(stroke
				(width 0.1)
				(type default)
			)
			(layer "F.Fab")
		)
		(fp_line
			(start -0.67945 -0.305054)
			(end -0.12065 -0.305054)
			(stroke
				(width 0.1)
				(type default)
			)
			(layer "F.Fab")
		)
		(fp_line
			(start -0.12065 -0.305054)
			(end -0.12065 -0.2794)
			(stroke
				(width 0.1)
				(type default)
			)
			(layer "F.Fab")
		)
		(pad "1" smd circle
			(at -0.40005 0 270)
			(size 0 0)
			(layers "F.Cu" "F.Mask" "F.Paste")
			(net "GND")
		)
		(pad "2" smd circle
			(at 0.40005 0 270)
			(size 0 0)
			(layers "F.Cu" "F.Mask" "F.Paste")
			(net "PVCCIN_CPU0_VREF")
		)
	)
)
